(kicad_pcb
	(version 20241229)
	(generator "pcbnew")
	(generator_version "9.0")
	(general
		(thickness 1.63)
		(legacy_teardrops no)
	)
	(paper "A4")
	(title_block
		(title "CM4 Baseboard")
		(date "2026-01-05")
		(rev "1.1.1")
		(company "Antmicro Ltd")
		(comment 1 "www.antmicro.com")
		(comment 9 "footprints 372-373 of 506")
	)
	(layers
		(0 "F.Cu" signal)
		(4 "In1.Cu" power)
		(6 "In2.Cu" power)
		(8 "In3.Cu" signal)
		(10 "In4.Cu" signal)
		(2 "B.Cu" signal)
		(9 "F.Adhes" user "F.Adhesive")
		(11 "B.Adhes" user "B.Adhesive")
		(13 "F.Paste" user)
		(15 "B.Paste" user)
		(5 "F.SilkS" user "F.Silkscreen")
		(7 "B.SilkS" user "B.Silkscreen")
		(1 "F.Mask" user)
		(3 "B.Mask" user)
		(17 "Dwgs.User" user "User.Drawings")
		(19 "Cmts.User" user "User.Comments")
		(21 "Eco1.User" user "User.Eco1")
		(23 "Eco2.User" user "User.Eco2")
		(25 "Edge.Cuts" user)
		(27 "Margin" user)
		(31 "F.CrtYd" user "F.Courtyard")
		(29 "B.CrtYd" user "B.Courtyard")
		(35 "F.Fab" user)
		(33 "B.Fab" user)
	)
	(footprint "antmicro-footprints:R_0603_1608Metric"
		(layer "B.Cu")
		(at 117.867962 135.0415 90)
		(descr "Resistor SMD 0603")
		(tags "resistor SMD 0603")
		(property "Reference" "R322"
			(at -4.015 0.14 90)
			(layer "B.SilkS")
			(effects
				(font
					(size 0.7 0.7)
					(thickness 0.15)
				)
				(justify right bottom mirror)
			)
		)
		(property "Value" "R_0R_22.4A_0603"
			(at 0 -1.6 90)
			(layer "B.Fab")
			(effects
				(font
					(size 0.7 0.7)
					(thickness 0.15)
				)
				(justify right bottom mirror)
			)
		)
		(property "Datasheet" "https://fscdn.rohm.com/en/products/databook/datasheet/passive/resistor/chip_resistor/pmr-jpw-e.pdf"
			(at 0 0 90)
			(layer "B.Fab")
			(hide yes)
			(effects
				(font
					(size 1.27 1.27)
					(thickness 0.15)
				)
			)
		)
		(property "Manufacturer" "ROHM Semiconductor"
			(at 0 0 90)
			(unlocked yes)
			(layer "B.Fab")
			(hide yes)
			(effects
				(font
					(size 1 1)
					(thickness 0.15)
				)
				(justify mirror)
			)
		)
		(property "MPN" "PMR03EZPJ000"
			(at 0 0 90)
			(unlocked yes)
			(layer "B.Fab")
			(hide yes)
			(effects
				(font
					(size 1 1)
					(thickness 0.15)
				)
				(justify mirror)
			)
		)
		(property "Val" "0R"
			(at 0 0 90)
			(unlocked yes)
			(layer "B.Fab")
			(hide yes)
			(effects
				(font
					(size 1 1)
					(thickness 0.15)
				)
				(justify mirror)
			)
		)
		(property "Author" "Antmicro"
			(at 0 0 90)
			(unlocked yes)
			(layer "B.Fab")
			(hide yes)
			(effects
				(font
					(size 1 1)
					(thickness 0.15)
				)
				(justify mirror)
			)
		)
		(property "License" "Apache-2.0"
			(at 0 0 90)
			(unlocked yes)
			(layer "B.Fab")
			(hide yes)
			(effects
				(font
					(size 1 1)
					(thickness 0.15)
				)
				(justify mirror)
			)
		)
		(property "Max. Curr." "22.4A"
			(at 0 0 90)
			(unlocked yes)
			(layer "B.Fab")
			(hide yes)
			(effects
				(font
					(size 1 1)
					(thickness 0.15)
				)
				(justify mirror)
			)
		)
		(property "Tolerance" "template_tolerance"
			(at 0 0 90)
			(unlocked yes)
			(layer "B.Fab")
			(hide yes)
			(effects
				(font
					(size 1 1)
					(thickness 0.15)
				)
				(justify mirror)
			)
		)
		(sheetname "/Supply/")
		(sheetfile "supply.kicad_sch")
		(attr smd)
		(fp_line
			(start -0.15 -0.4)
			(end 0.15 -0.4)
			(stroke
				(width 0.15)
				(type solid)
			)
			(layer "B.SilkS")
		)
		(fp_line
			(start -0.15 0.4)
			(end 0.15 0.4)
			(stroke
				(width 0.15)
				(type solid)
			)
			(layer "B.SilkS")
		)
		(fp_rect
			(start -1.25 0.65)
			(end 1.25 -0.65)
			(stroke
				(width 0.05)
				(type solid)
			)
			(fill no)
			(layer "B.CrtYd")
		)
		(fp_rect
			(start -0.8 0.4)
			(end 0.8 -0.4)
			(stroke
				(width 0.15)
				(type solid)
			)
			(fill no)
			(layer "B.Fab")
		)
		(fp_text user "License: Apache-2.0"
			(at -1.25 -5.9 270)
			(layer "B.Fab")
			(effects
				(font
					(size 0.7 0.7)
					(thickness 0.15)
				)
				(justify left bottom mirror)
			)
		)
		(fp_text user "Author: Antmicro"
			(at -1.25 -4.9 270)
			(layer "B.Fab")
			(effects
				(font
					(size 0.7 0.7)
					(thickness 0.15)
				)
				(justify left bottom mirror)
			)
		)
		(fp_text user "${REFERENCE}"
			(at -1.25 -3.898 270)
			(layer "B.Fab")
			(effects
				(font
					(size 0.7 0.7)
					(thickness 0.15)
				)
				(justify left bottom mirror)
			)
		)
		(pad "1" smd roundrect
			(at -0.7 0 90)
			(size 0.8 1)
			(layers "B.Cu" "B.Mask" "B.Paste")
			(roundrect_rratio 0.2)
			(net 78 "/Supply/OUT_M2")
			(pintype "passive")
		)
		(pad "2" smd roundrect
			(at 0.7 0 90)
			(size 0.8 1)
			(layers "B.Cu" "B.Mask" "B.Paste")
			(roundrect_rratio 0.2)
			(net 65 "3V3_SSD")
			(pintype "passive")
		)
	)
	(footprint "antmicro-footprints:Conn_FFC_WE_68715014x22"
		(layer "B.Cu")
		(at 139.617962 135.7165 -90)
		(property "Reference" "J601"
			(at -12.64 3.31 90)
			(layer "B.SilkS")
			(effects
				(font
					(size 0.7 0.7)
					(thickness 0.15)
				)
				(justify left bottom mirror)
			)
		)
		(property "Value" "Conn_FFC_WE_68715014522"
			(at 0 -4.5 90)
			(layer "B.Fab")
			(effects
				(font
					(size 0.7 0.7)
					(thickness 0.15)
				)
				(justify left bottom mirror)
			)
		)
		(property "Datasheet" "https://www.we-online.com/components/products/datasheet/68715014522.pdf"
			(at 0 0 270)
			(layer "B.Fab")
			(hide yes)
			(effects
				(font
					(size 1.27 1.27)
					(thickness 0.15)
				)
			)
		)
		(property "MPN" "68715014522"
			(at 0 0 270)
			(unlocked yes)
			(layer "B.Fab")
			(hide yes)
			(effects
				(font
					(size 1 1)
					(thickness 0.15)
				)
				(justify mirror)
			)
		)
		(property "Manufacturer" "Würth Elektronik"
			(at 0 0 270)
			(unlocked yes)
			(layer "B.Fab")
			(hide yes)
			(effects
				(font
					(size 1 1)
					(thickness 0.15)
				)
				(justify mirror)
			)
		)
		(property "Author" "Antmicro"
			(at 0 0 270)
			(unlocked yes)
			(layer "B.Fab")
			(hide yes)
			(effects
				(font
					(size 1 1)
					(thickness 0.15)
				)
				(justify mirror)
			)
		)
		(property "License" "Apache-2.0"
			(at 0 0 270)
			(unlocked yes)
			(layer "B.Fab")
			(hide yes)
			(effects
				(font
					(size 1 1)
					(thickness 0.15)
				)
				(justify mirror)
			)
		)
		(sheetname "/CSI/")
		(sheetfile "csi.kicad_sch")
		(attr smd)
		(fp_line
			(start -12.5 2.976)
			(end 12.499 2.976)
			(stroke
				(width 0.15)
				(type solid)
			)
			(layer "B.SilkS")
		)
		(fp_line
			(start -15.85 2.15)
			(end -12.5 2.15)
			(stroke
				(width 0.15)
				(type solid)
			)
			(layer "B.SilkS")
		)
		(fp_line
			(start -12.5 2.15)
			(end -12.5 2.976)
			(stroke
				(width 0.15)
				(type solid)
			)
			(layer "B.SilkS")
		)
		(fp_line
			(start 12.499 2.15)
			(end 12.499 2.976)
			(stroke
				(width 0.15)
				(type solid)
			)
			(layer "B.SilkS")
		)
		(fp_line
			(start 15.85 2.15)
			(end 12.499 2.15)
			(stroke
				(width 0.15)
				(type solid)
			)
			(layer "B.SilkS")
		)
		(fp_line
			(start -15.85 -2.7)
			(end -15.85 2.15)
			(stroke
				(width 0.15)
				(type solid)
			)
			(layer "B.SilkS")
		)
		(fp_line
			(start 15.85 -2.7)
			(end 15.85 2.15)
			(stroke
				(width 0.15)
				(type solid)
			)
			(layer "B.SilkS")
		)
		(fp_line
			(start 15.85 -2.7)
			(end -15.85 -2.7)
			(stroke
				(width 0.15)
				(type solid)
			)
			(layer "B.SilkS")
		)
		(fp_circle
			(center -12.9 2.9)
			(end -12.85 2.85)
			(stroke
				(width 0.15)
				(type solid)
			)
			(fill yes)
			(layer "B.SilkS")
		)
		(fp_rect
			(start -16.2 3.25)
			(end 16.2 -3.55)
			(stroke
				(width 0.05)
				(type solid)
			)
			(fill no)
			(layer "B.CrtYd")
		)
		(fp_text user "${REFERENCE}"
			(at -16.2 -5.9 90)
			(layer "B.Fab")
			(effects
				(font
					(size 0.7 0.7)
					(thickness 0.15)
				)
				(justify left bottom mirror)
			)
		)
		(fp_text user "Author: Antmicro"
			(at -16.2 -6.9 90)
			(layer "B.Fab")
			(effects
				(font
					(size 0.7 0.7)
					(thickness 0.15)
				)
				(justify left bottom mirror)
			)
		)
		(fp_text user "License: Apache-2.0"
			(at -16.2 -7.9 90)
			(layer "B.Fab")
			(effects
				(font
					(size 0.7 0.7)
					(thickness 0.15)
				)
				(justify left bottom mirror)
			)
		)
		(pad "1" smd roundrect
			(at -12.25 2.15 270)
			(size 0.3 1.2)
			(layers "B.Cu" "B.Mask" "B.Paste")
			(roundrect_rratio 0.25)
			(net 269 "unconnected-(J601-Pad1)")
			(pintype "passive+no_connect")
		)
		(pad "2" smd roundrect
			(at -11.75 2.15 270)
			(size 0.3 1.2)
			(layers "B.Cu" "B.Mask" "B.Paste")
			(roundrect_rratio 0.25)
			(net 270 "unconnected-(J601-Pad2)")
			(pintype "passive+no_connect")
		)
		(pad "3" smd roundrect
			(at -11.25 2.15 270)
			(size 0.3 1.2)
			(layers "B.Cu" "B.Mask" "B.Paste")
			(roundrect_rratio 0.25)
			(net 271 "unconnected-(J601-Pad3)")
			(pintype "passive+no_connect")
		)
		(pad "4" smd roundrect
			(at -10.75 2.15 270)
			(size 0.3 1.2)
			(layers "B.Cu" "B.Mask" "B.Paste")
			(roundrect_rratio 0.25)
			(net 272 "unconnected-(J601-Pad4)")
			(pintype "passive+no_connect")
		)
		(pad "5" smd roundrect
			(at -10.25 2.15 270)
			(size 0.3 1.2)
			(layers "B.Cu" "B.Mask" "B.Paste")
			(roundrect_rratio 0.25)
			(net 57 "/CSI/CSI0.D1_N")
			(pintype "passive")
		)
		(pad "6" smd roundrect
			(at -9.75 2.15 270)
			(size 0.3 1.2)
			(layers "B.Cu" "B.Mask" "B.Paste")
			(roundrect_rratio 0.25)
			(net 67 "/CSI/CSI0.D1_P")
			(pintype "passive")
		)
		(pad "7" smd roundrect
			(at -9.25 2.15 270)
			(size 0.3 1.2)
			(layers "B.Cu" "B.Mask" "B.Paste")
			(roundrect_rratio 0.25)
			(net 53 "/CSI/CSI0.D0_N")
			(pintype "passive")
		)
		(pad "8" smd roundrect
			(at -8.75 2.15 270)
			(size 0.3 1.2)
			(layers "B.Cu" "B.Mask" "B.Paste")
			(roundrect_rratio 0.25)
			(net 55 "/CSI/CSI0.D0_P")
			(pintype "passive")
		)
		(pad "9" smd roundrect
			(at -8.25 2.15 270)
			(size 0.3 1.2)
			(layers "B.Cu" "B.Mask" "B.Paste")
			(roundrect_rratio 0.25)
			(net 3 "GND")
			(pintype "passive")
		)
		(pad "10" smd roundrect
			(at -7.75 2.15 270)
			(size 0.3 1.2)
			(layers "B.Cu" "B.Mask" "B.Paste")
			(roundrect_rratio 0.25)
			(net 69 "/CSI/CSI0.CLK_N")
			(pintype "passive")
		)
		(pad "11" smd roundrect
			(at -7.25 2.15 270)
			(size 0.3 1.2)
			(layers "B.Cu" "B.Mask" "B.Paste")
			(roundrect_rratio 0.25)
			(net 71 "/CSI/CSI0.CLK_P")
			(pintype "passive")
		)
		(pad "12" smd roundrect
			(at -6.75 2.15 270)
			(size 0.3 1.2)
			(layers "B.Cu" "B.Mask" "B.Paste")
			(roundrect_rratio 0.25)
			(net 3 "GND")
			(pintype "passive")
		)
		(pad "13" smd roundrect
			(at -6.25 2.15 270)
			(size 0.3 1.2)
			(layers "B.Cu" "B.Mask" "B.Paste")
			(roundrect_rratio 0.25)
			(net 273 "unconnected-(J601-Pad13)")
			(pintype "passive+no_connect")
		)
		(pad "14" smd roundrect
			(at -5.75 2.15 270)
			(size 0.3 1.2)
			(layers "B.Cu" "B.Mask" "B.Paste")
			(roundrect_rratio 0.25)
			(net 280 "unconnected-(J601-Pad14)")
			(pintype "passive+no_connect")
		)
		(pad "15" smd roundrect
			(at -5.25 2.15 270)
			(size 0.3 1.2)
			(layers "B.Cu" "B.Mask" "B.Paste")
			(roundrect_rratio 0.25)
			(net 3 "GND")
			(pintype "passive")
		)
		(pad "16" smd roundrect
			(at -4.75 2.15 270)
			(size 0.3 1.2)
			(layers "B.Cu" "B.Mask" "B.Paste")
			(roundrect_rratio 0.25)
			(net 289 "unconnected-(J601-Pad16)")
			(pintype "passive+no_connect")
		)
		(pad "17" smd roundrect
			(at -4.25 2.15 270)
			(size 0.3 1.2)
			(layers "B.Cu" "B.Mask" "B.Paste")
			(roundrect_rratio 0.25)
			(net 290 "unconnected-(J601-Pad17)")
			(pintype "passive+no_connect")
		)
		(pad "18" smd roundrect
			(at -3.75 2.15 270)
			(size 0.3 1.2)
			(layers "B.Cu" "B.Mask" "B.Paste")
			(roundrect_rratio 0.25)
			(net 3 "GND")
			(pintype "passive")
		)
		(pad "19" smd roundrect
			(at -3.25 2.15 270)
			(size 0.3 1.2)
			(layers "B.Cu" "B.Mask" "B.Paste")
			(roundrect_rratio 0.25)
			(net 68 "/CSI/CSI1.D3_N")
			(pintype "passive")
		)
		(pad "20" smd roundrect
			(at -2.75 2.15 270)
			(size 0.3 1.2)
			(layers "B.Cu" "B.Mask" "B.Paste")
			(roundrect_rratio 0.25)
			(net 70 "/CSI/CSI1.D3_P")
			(pintype "passive")
		)
		(pad "21" smd roundrect
			(at -2.25 2.15 270)
			(size 0.3 1.2)
			(layers "B.Cu" "B.Mask" "B.Paste")
			(roundrect_rratio 0.25)
			(net 56 "/CSI/CSI1.D2_N")
			(pintype "passive")
		)
		(pad "22" smd roundrect
			(at -1.75 2.15 270)
			(size 0.3 1.2)
			(layers "B.Cu" "B.Mask" "B.Paste")
			(roundrect_rratio 0.25)
			(net 58 "/CSI/CSI1.D2_P")
			(pintype "passive")
		)
		(pad "23" smd roundrect
			(at -1.25 2.15 270)
			(size 0.3 1.2)
			(layers "B.Cu" "B.Mask" "B.Paste")
			(roundrect_rratio 0.25)
			(net 46 "/CSI/CSI1.D1_N")
			(pintype "passive")
		)
		(pad "24" smd roundrect
			(at -0.75 2.15 270)
			(size 0.3 1.2)
			(layers "B.Cu" "B.Mask" "B.Paste")
			(roundrect_rratio 0.25)
			(net 50 "/CSI/CSI1.D1_P")
			(pintype "passive")
		)
		(pad "25" smd roundrect
			(at -0.25 2.15 270)
			(size 0.3 1.2)
			(layers "B.Cu" "B.Mask" "B.Paste")
			(roundrect_rratio 0.25)
			(net 42 "/CSI/CSI1.D0_N")
			(pintype "passive")
		)
		(pad "26" smd roundrect
			(at 0.248 2.15 270)
			(size 0.3 1.2)
			(layers "B.Cu" "B.Mask" "B.Paste")
			(roundrect_rratio 0.25)
			(net 44 "/CSI/CSI1.D0_P")
			(pintype "passive")
		)
		(pad "27" smd roundrect
			(at 0.748 2.15 270)
			(size 0.3 1.2)
			(layers "B.Cu" "B.Mask" "B.Paste")
			(roundrect_rratio 0.25)
			(net 3 "GND")
			(pintype "passive")
		)
		(pad "28" smd roundrect
			(at 1.249 2.15 270)
			(size 0.3 1.2)
			(layers "B.Cu" "B.Mask" "B.Paste")
			(roundrect_rratio 0.25)
			(net 52 "/CSI/CSI1.CLK_N")
			(pintype "passive")
		)
		(pad "29" smd roundrect
			(at 1.749 2.15 270)
			(size 0.3 1.2)
			(layers "B.Cu" "B.Mask" "B.Paste")
			(roundrect_rratio 0.25)
			(net 54 "/CSI/CSI1.CLK_P")
			(pintype "passive")
		)
		(pad "30" smd roundrect
			(at 2.249 2.15 270)
			(size 0.3 1.2)
			(layers "B.Cu" "B.Mask" "B.Paste")
			(roundrect_rratio 0.25)
			(net 3 "GND")
			(pintype "passive")
		)
		(pad "31" smd roundrect
			(at 2.749 2.15 270)
			(size 0.3 1.2)
			(layers "B.Cu" "B.Mask" "B.Paste")
			(roundrect_rratio 0.25)
			(net 291 "unconnected-(J601-Pad31)")
			(pintype "passive+no_connect")
		)
		(pad "32" smd roundrect
			(at 3.249 2.15 270)
			(size 0.3 1.2)
			(layers "B.Cu" "B.Mask" "B.Paste")
			(roundrect_rratio 0.25)
			(net 274 "/CSI/CamCtrl.VSYNC0")
			(pintype "passive")
		)
		(pad "33" smd roundrect
			(at 3.749 2.15 270)
			(size 0.3 1.2)
			(layers "B.Cu" "B.Mask" "B.Paste")
			(roundrect_rratio 0.25)
			(net 292 "unconnected-(J601-Pad33)")
			(pintype "passive+no_connect")
		)
		(pad "34" smd roundrect
			(at 4.248 2.15 270)
			(size 0.3 1.2)
			(layers "B.Cu" "B.Mask" "B.Paste")
			(roundrect_rratio 0.25)
			(net 275 "/CSI/CamCtrl.VSYNC1")
			(pintype "passive")
		)
		(pad "35" smd roundrect
			(at 4.748 2.15 270)
			(size 0.3 1.2)
			(layers "B.Cu" "B.Mask" "B.Paste")
			(roundrect_rratio 0.25)
			(net 293 "unconnected-(J601-Pad35)")
			(pintype "passive+no_connect")
		)
		(pad "36" smd roundrect
			(at 5.248 2.15 270)
			(size 0.3 1.2)
			(layers "B.Cu" "B.Mask" "B.Paste")
			(roundrect_rratio 0.25)
			(net 294 "unconnected-(J601-Pad36)")
			(pintype "passive+no_connect")
		)
		(pad "37" smd roundrect
			(at 5.749 2.15 270)
			(size 0.3 1.2)
			(layers "B.Cu" "B.Mask" "B.Paste")
			(roundrect_rratio 0.25)
			(net 295 "unconnected-(J601-Pad37)")
			(pintype "passive+no_connect")
		)
		(pad "38" smd roundrect
			(at 6.249 2.15 270)
			(size 0.3 1.2)
			(layers "B.Cu" "B.Mask" "B.Paste")
			(roundrect_rratio 0.25)
			(net 296 "unconnected-(J601-Pad38)")
			(pintype "passive+no_connect")
		)
		(pad "39" smd roundrect
			(at 6.749 2.15 270)
			(size 0.3 1.2)
			(layers "B.Cu" "B.Mask" "B.Paste")
			(roundrect_rratio 0.25)
			(net 141 "/CSI/I_{2}C_CSI0.SDA")
			(pintype "passive")
		)
		(pad "40" smd roundrect
			(at 7.249 2.15 270)
			(size 0.3 1.2)
			(layers "B.Cu" "B.Mask" "B.Paste")
			(roundrect_rratio 0.25)
			(net 140 "/CSI/I_{2}C_CSI0.SCL")
			(pintype "passive")
		)
		(pad "41" smd roundrect
			(at 7.749 2.15 270)
			(size 0.3 1.2)
			(layers "B.Cu" "B.Mask" "B.Paste")
			(roundrect_rratio 0.25)
			(net 143 "/CSI/I_{2}C1.SDA")
			(pintype "passive")
		)
		(pad "42" smd roundrect
			(at 8.249 2.15 270)
			(size 0.3 1.2)
			(layers "B.Cu" "B.Mask" "B.Paste")
			(roundrect_rratio 0.25)
			(net 142 "/CSI/I_{2}C1.SCL")
			(pintype "passive")
		)
		(pad "43" smd roundrect
			(at 8.749 2.15 270)
			(size 0.3 1.2)
			(layers "B.Cu" "B.Mask" "B.Paste")
			(roundrect_rratio 0.25)
			(net 297 "unconnected-(J601-Pad43)")
			(pintype "passive+no_connect")
		)
		(pad "44" smd roundrect
			(at 9.249 2.15 270)
			(size 0.3 1.2)
			(layers "B.Cu" "B.Mask" "B.Paste")
			(roundrect_rratio 0.25)
			(net 298 "unconnected-(J601-Pad44)")
			(pintype "passive+no_connect")
		)
		(pad "45" smd roundrect
			(at 9.749 2.15 270)
			(size 0.3 1.2)
			(layers "B.Cu" "B.Mask" "B.Paste")
			(roundrect_rratio 0.25)
			(net 299 "unconnected-(J601-Pad45)")
			(pintype "passive+no_connect")
		)
		(pad "46" smd roundrect
			(at 10.249 2.15 270)
			(size 0.3 1.2)
			(layers "B.Cu" "B.Mask" "B.Paste")
			(roundrect_rratio 0.25)
			(net 300 "unconnected-(J601-Pad46)")
			(pintype "passive+no_connect")
		)
		(pad "47" smd roundrect
			(at 10.749 2.15 270)
			(size 0.3 1.2)
			(layers "B.Cu" "B.Mask" "B.Paste")
			(roundrect_rratio 0.25)
			(net 19 "/CSI/CSI_3V3")
			(pintype "passive")
		)
		(pad "48" smd roundrect
			(at 11.249 2.15 270)
			(size 0.3 1.2)
			(layers "B.Cu" "B.Mask" "B.Paste")
			(roundrect_rratio 0.25)
			(net 19 "/CSI/CSI_3V3")
			(pintype "passive")
		)
		(pad "49" smd roundrect
			(at 11.749 2.15 270)
			(size 0.3 1.2)
			(layers "B.Cu" "B.Mask" "B.Paste")
			(roundrect_rratio 0.25)
			(net 20 "/CSI/CSI_5V")
			(pintype "passive")
		)
		(pad "50" smd roundrect
			(at 12.249 2.15 270)
			(size 0.3 1.2)
			(layers "B.Cu" "B.Mask" "B.Paste")
			(roundrect_rratio 0.25)
			(net 20 "/CSI/CSI_5V")
			(pintype "passive")
		)
		(pad "MP1" smd roundrect
			(at -14.198 0.3 270)
			(size 2.7 3)
			(layers "B.Cu" "B.Mask" "B.Paste")
			(roundrect_rratio 0.05)
			(net 3 "GND")
			(pinfunction "MP")
			(pintype "passive")
		)
		(pad "MP2" smd roundrect
			(at 14.198 0.3 270)
			(size 2.7 3)
			(layers "B.Cu" "B.Mask" "B.Paste")
			(roundrect_rratio 0.05)
			(net 3 "GND")
			(pinfunction "MP")
			(pintype "passive")
		)
	)
)
